(kicad_pcb
	(version 20260206)
	(generator "pcbnew")
	(generator_version "10.0")
	(general
		(thickness 1.6)
		(legacy_teardrops no)
	)
	(paper "A4")
	(title_block
		(title "v2-pdb — ms_pdb_v2.brd")
		(comment 1 "Open CloudServer (Microsoft) / footprints 236-246 of 348")
	)
	(layers
		(0 "F.Cu" signal "TOP")
		(4 "In1.Cu" signal "GND")
		(6 "In2.Cu" signal "IN1")
		(8 "In3.Cu" signal "VCC")
		(10 "In4.Cu" signal "VCC1")
		(12 "In5.Cu" signal "IN2")
		(14 "In6.Cu" signal "GND1")
		(2 "B.Cu" signal "BOTTOM")
		(9 "F.Adhes" user "F.Adhesive")
		(11 "B.Adhes" user "B.Adhesive")
		(13 "F.Paste" user "Package Geometry/Pastemask Top")
		(15 "B.Paste" user "Package Geometry/Pastemask Bottom")
		(5 "F.SilkS" user "Ref Des/Silkscreen Top")
		(7 "B.SilkS" user "Ref Des/Silkscreen Bottom")
		(1 "F.Mask" user "Board Geometry/Soldermask Top")
		(3 "B.Mask" user "Board Geometry/Soldermask Bottom")
		(17 "Dwgs.User" user "User.Drawings")
		(19 "Cmts.User" user "User.Comments")
		(21 "Eco1.User" user "User.Eco1")
		(23 "Eco2.User" user "User.Eco2")
		(25 "Edge.Cuts" user "Board Geometry/Outline")
		(27 "Margin" user)
		(31 "F.CrtYd" user "Package Geometry/Place Bound Top")
		(29 "B.CrtYd" user "Package Geometry/Place Bound Bottom")
		(35 "F.Fab" user "Ref Des/Assembly Top")
		(33 "B.Fab" user "Ref Des/Assembly Bottom")
	)
	(footprint ""
		(layer "F.Cu")
		(at 39.858442 -110.774226 180)
		(property "Reference" "R3"
			(at -1.626616 0.658622 0)
			(unlocked yes)
			(layer "F.SilkS")
			(effects
				(font
					(size 0.7874 0.5842)
					(thickness 0.1524)
				)
				(justify left)
			)
		)
		(property "Value" ""
			(at 0 0 180)
			(layer "F.Fab")
			(effects
				(font
					(size 1.27 1.27)
				)
			)
		)
		(duplicate_pad_numbers_are_jumpers no)
		(fp_line
			(start 0.7874 0.4064)
			(end -0.7874 0.4064)
			(stroke
				(width 0.1524)
				(type default)
			)
			(layer "F.SilkS")
		)
		(fp_line
			(start 0.7874 -0.4064)
			(end 0.7874 0.4064)
			(stroke
				(width 0.1524)
				(type default)
			)
			(layer "F.SilkS")
		)
		(fp_line
			(start -0.7874 0.4064)
			(end -0.7874 -0.4064)
			(stroke
				(width 0.1524)
				(type default)
			)
			(layer "F.SilkS")
		)
		(fp_line
			(start -0.7874 -0.4064)
			(end 0.7874 -0.4064)
			(stroke
				(width 0.1524)
				(type default)
			)
			(layer "F.SilkS")
		)
		(fp_poly
			(pts
				(xy -0.508 0.2794) (xy -0.508 0.2286) (xy -0.635 0.2286) (xy -0.635 -0.254) (xy -0.5334 -0.254)
				(xy -0.5334 -0.2794) (xy 0.5334 -0.2794) (xy 0.5334 -0.254) (xy 0.635 -0.254) (xy 0.635 0.254) (xy 0.5334 0.254)
				(xy 0.5334 0.2794)
			)
			(stroke
				(width 0)
				(type default)
			)
			(fill no)
			(layer "F.CrtYd")
		)
		(pad "1" smd rect
			(at 0.40005 0 180)
			(size 0.4572 0.508)
			(layers "F.Cu" "F.Mask" "F.Paste")
			(net "PSU2_REMOTE_P")
		)
		(pad "2" smd rect
			(at -0.40005 0 180)
			(size 0.4572 0.508)
			(layers "F.Cu" "F.Mask" "F.Paste")
			(net "P12V")
		)
	)
	(footprint ""
		(layer "F.Cu")
		(at 14.309598 -223.205294)
		(property "Reference" ""
			(at 0 0 0)
			(layer "F.SilkS")
			(hide yes)
			(effects
				(font
					(size 1.27 1.27)
				)
			)
		)
		(property "Value" ""
			(at 0 0 0)
			(layer "F.Fab")
			(effects
				(font
					(size 1.27 1.27)
				)
			)
		)
		(duplicate_pad_numbers_are_jumpers no)
		(fp_poly
			(pts
				(arc
					(start 1.4986 0)
					(mid -1.4986 0)
					(end 1.4986 0)
				)
			)
			(stroke
				(width 0)
				(type default)
			)
			(fill no)
			(layer "F.CrtYd")
		)
		(pad "1" smd circle
			(at 0 0)
			(size 0.9906 0.9906)
			(layers "F.Cu" "F.Mask" "F.Paste")
			(net "Net_196")
		)
		(zone
			(layer "F.Cu")
			(hatch none 0.5)
			(connect_pads
				(clearance 0)
			)
			(min_thickness 0.25)
			(keepout
				(tracks not_allowed)
				(vias allowed)
				(pads allowed)
				(copperpour not_allowed)
				(footprints allowed)
			)
			(placement
				(enabled no)
				(sheetname "")
			)
			(fill
				(thermal_gap 0.5)
				(thermal_bridge_width 0.5)
				(island_removal_mode 0)
			)
			(polygon
				(pts
					(arc
						(start 15.935198 -223.205294)
						(mid 12.683998 -223.205294)
						(end 15.935198 -223.205294)
					)
				)
			)
		)
	)
	(footprint ""
		(layer "F.Cu")
		(at 27.246072 -20.26412 -90)
		(property "Reference" "R87"
			(at -1.149604 0.97536 90)
			(unlocked yes)
			(layer "F.SilkS")
			(effects
				(font
					(size 0.7874 0.5842)
					(thickness 0.1524)
				)
				(justify left)
			)
		)
		(property "Value" ""
			(at 0 0 270)
			(layer "F.Fab")
			(effects
				(font
					(size 1.27 1.27)
				)
			)
		)
		(duplicate_pad_numbers_are_jumpers no)
		(fp_line
			(start -0.7874 0.4064)
			(end -0.7874 -0.4064)
			(stroke
				(width 0.1524)
				(type default)
			)
			(layer "F.SilkS")
		)
		(fp_line
			(start 0.7874 0.4064)
			(end -0.7874 0.4064)
			(stroke
				(width 0.1524)
				(type default)
			)
			(layer "F.SilkS")
		)
		(fp_line
			(start -0.7874 -0.4064)
			(end 0.7874 -0.4064)
			(stroke
				(width 0.1524)
				(type default)
			)
			(layer "F.SilkS")
		)
		(fp_line
			(start 0.7874 -0.4064)
			(end 0.7874 0.4064)
			(stroke
				(width 0.1524)
				(type default)
			)
			(layer "F.SilkS")
		)
		(fp_poly
			(pts
				(xy -0.508 0.2794) (xy -0.508 0.2286) (xy -0.635 0.2286) (xy -0.635 -0.254) (xy -0.5334 -0.254)
				(xy -0.5334 -0.2794) (xy 0.5334 -0.2794) (xy 0.5334 -0.254) (xy 0.635 -0.254) (xy 0.635 0.254) (xy 0.5334 0.254)
				(xy 0.5334 0.2794)
			)
			(stroke
				(width 0)
				(type default)
			)
			(fill no)
			(layer "F.CrtYd")
		)
		(pad "1" smd rect
			(at 0.40005 0 270)
			(size 0.4572 0.508)
			(layers "F.Cu" "F.Mask" "F.Paste")
			(net "PSU1_REMOTE_N")
		)
		(pad "2" smd rect
			(at -0.40005 0 270)
			(size 0.4572 0.508)
			(layers "F.Cu" "F.Mask" "F.Paste")
			(net "PSU1_REMOTE_R_N")
		)
	)
	(footprint ""
		(layer "F.Cu")
		(at 21.674074 -444.049658 180)
		(property "Reference" "C88"
			(at -0.189484 -7.234428 0)
			(unlocked yes)
			(layer "F.SilkS")
			(effects
				(font
					(size 0.7874 0.5842)
					(thickness 0.1524)
				)
				(justify left)
			)
		)
		(property "Value" ""
			(at 0 0 180)
			(layer "F.Fab")
			(effects
				(font
					(size 1.27 1.27)
				)
			)
		)
		(duplicate_pad_numbers_are_jumpers no)
		(fp_line
			(start 1.905 0.8636)
			(end -1.905 0.8636)
			(stroke
				(width 0.1524)
				(type default)
			)
			(layer "F.SilkS")
		)
		(fp_line
			(start 1.905 -0.8636)
			(end 1.905 0.8636)
			(stroke
				(width 0.1524)
				(type default)
			)
			(layer "F.SilkS")
		)
		(fp_line
			(start 0 0.8382)
			(end 0 -0.8382)
			(stroke
				(width 0.1524)
				(type default)
			)
			(layer "F.SilkS")
		)
		(fp_line
			(start -1.905 0.8636)
			(end -1.905 -0.8636)
			(stroke
				(width 0.1524)
				(type default)
			)
			(layer "F.SilkS")
		)
		(fp_line
			(start -1.905 -0.8636)
			(end 1.905 -0.8636)
			(stroke
				(width 0.1524)
				(type default)
			)
			(layer "F.SilkS")
		)
		(fp_rect
			(start -1.524 0.7366)
			(end 1.524 -0.7366)
			(stroke
				(width 0)
				(type default)
			)
			(fill no)
			(layer "F.CrtYd")
		)
		(pad "1" smd rect
			(at 0.94996 0 180)
			(size 1.1176 1.3716)
			(layers "F.Cu" "F.Mask" "F.Paste")
			(net "N42242336")
		)
		(pad "2" smd rect
			(at -0.94996 0 180)
			(size 1.1176 1.3716)
			(layers "F.Cu" "F.Mask" "F.Paste")
			(net "GND")
		)
	)
	(footprint ""
		(layer "F.Cu")
		(at 16.263366 -445.813434)
		(property "Reference" "C85"
			(at -1.079754 3.787394 0)
			(unlocked yes)
			(layer "F.SilkS")
			(effects
				(font
					(size 0.7874 0.5842)
					(thickness 0.1524)
				)
				(justify left)
			)
		)
		(property "Value" ""
			(at 0 0 0)
			(layer "F.Fab")
			(effects
				(font
					(size 1.27 1.27)
				)
			)
		)
		(duplicate_pad_numbers_are_jumpers no)
		(fp_line
			(start -1.905 -0.8636)
			(end 1.905 -0.8636)
			(stroke
				(width 0.1524)
				(type default)
			)
			(layer "F.SilkS")
		)
		(fp_line
			(start -1.905 0.8636)
			(end -1.905 -0.8636)
			(stroke
				(width 0.1524)
				(type default)
			)
			(layer "F.SilkS")
		)
		(fp_line
			(start 0 0.8382)
			(end 0 -0.8382)
			(stroke
				(width 0.1524)
				(type default)
			)
			(layer "F.SilkS")
		)
		(fp_line
			(start 1.905 -0.8636)
			(end 1.905 0.8636)
			(stroke
				(width 0.1524)
				(type default)
			)
			(layer "F.SilkS")
		)
		(fp_line
			(start 1.905 0.8636)
			(end -1.905 0.8636)
			(stroke
				(width 0.1524)
				(type default)
			)
			(layer "F.SilkS")
		)
		(fp_rect
			(start -1.524 0.7366)
			(end 1.524 -0.7366)
			(stroke
				(width 0)
				(type default)
			)
			(fill no)
			(layer "F.CrtYd")
		)
		(pad "1" smd rect
			(at 0.94996 0)
			(size 1.1176 1.3716)
			(layers "F.Cu" "F.Mask" "F.Paste")
			(net "P12V")
		)
		(pad "2" smd rect
			(at -0.94996 0)
			(size 1.1176 1.3716)
			(layers "F.Cu" "F.Mask" "F.Paste")
			(net "GND")
		)
	)
	(footprint ""
		(layer "F.Cu")
		(at 26.068274 -186.752992)
		(property "Reference" "R48"
			(at -3.997198 0.128524 0)
			(unlocked yes)
			(layer "F.SilkS")
			(effects
				(font
					(size 0.7874 0.5842)
					(thickness 0.1524)
				)
				(justify left)
			)
		)
		(property "Value" ""
			(at 0 0 0)
			(layer "F.Fab")
			(effects
				(font
					(size 1.27 1.27)
				)
			)
		)
		(duplicate_pad_numbers_are_jumpers no)
		(fp_line
			(start -0.7874 -0.4064)
			(end 0.7874 -0.4064)
			(stroke
				(width 0.1524)
				(type default)
			)
			(layer "F.SilkS")
		)
		(fp_line
			(start -0.7874 0.4064)
			(end -0.7874 -0.4064)
			(stroke
				(width 0.1524)
				(type default)
			)
			(layer "F.SilkS")
		)
		(fp_line
			(start 0.7874 -0.4064)
			(end 0.7874 0.4064)
			(stroke
				(width 0.1524)
				(type default)
			)
			(layer "F.SilkS")
		)
		(fp_line
			(start 0.7874 0.4064)
			(end -0.7874 0.4064)
			(stroke
				(width 0.1524)
				(type default)
			)
			(layer "F.SilkS")
		)
		(fp_poly
			(pts
				(xy -0.508 0.2794) (xy -0.508 0.2286) (xy -0.635 0.2286) (xy -0.635 -0.254) (xy -0.5334 -0.254)
				(xy -0.5334 -0.2794) (xy 0.5334 -0.2794) (xy 0.5334 -0.254) (xy 0.635 -0.254) (xy 0.635 0.254) (xy 0.5334 0.254)
				(xy 0.5334 0.2794)
			)
			(stroke
				(width 0)
				(type default)
			)
			(fill no)
			(layer "F.CrtYd")
		)
		(pad "1" smd rect
			(at 0.40005 0)
			(size 0.4572 0.508)
			(layers "F.Cu" "F.Mask" "F.Paste")
			(net "PSU3_PS_KILL")
		)
		(pad "2" smd rect
			(at -0.40005 0)
			(size 0.4572 0.508)
			(layers "F.Cu" "F.Mask" "F.Paste")
			(net "GND")
		)
	)
	(footprint ""
		(layer "F.Cu")
		(at 39.821358 -18.414238)
		(property "Reference" "R40"
			(at 1.662938 0.015494 0)
			(unlocked yes)
			(layer "F.SilkS")
			(effects
				(font
					(size 0.7874 0.5842)
					(thickness 0.1524)
				)
				(justify left)
			)
		)
		(property "Value" ""
			(at 0 0 0)
			(layer "F.Fab")
			(effects
				(font
					(size 1.27 1.27)
				)
			)
		)
		(duplicate_pad_numbers_are_jumpers no)
		(fp_line
			(start -0.7874 -0.4064)
			(end 0.7874 -0.4064)
			(stroke
				(width 0.1524)
				(type default)
			)
			(layer "F.SilkS")
		)
		(fp_line
			(start -0.7874 0.4064)
			(end -0.7874 -0.4064)
			(stroke
				(width 0.1524)
				(type default)
			)
			(layer "F.SilkS")
		)
		(fp_line
			(start 0.7874 -0.4064)
			(end 0.7874 0.4064)
			(stroke
				(width 0.1524)
				(type default)
			)
			(layer "F.SilkS")
		)
		(fp_line
			(start 0.7874 0.4064)
			(end -0.7874 0.4064)
			(stroke
				(width 0.1524)
				(type default)
			)
			(layer "F.SilkS")
		)
		(fp_poly
			(pts
				(xy -0.508 0.2794) (xy -0.508 0.2286) (xy -0.635 0.2286) (xy -0.635 -0.254) (xy -0.5334 -0.254)
				(xy -0.5334 -0.2794) (xy 0.5334 -0.2794) (xy 0.5334 -0.254) (xy 0.635 -0.254) (xy 0.635 0.254) (xy 0.5334 0.254)
				(xy 0.5334 0.2794)
			)
			(stroke
				(width 0)
				(type default)
			)
			(fill no)
			(layer "F.CrtYd")
		)
		(pad "1" smd rect
			(at 0.40005 0)
			(size 0.4572 0.508)
			(layers "F.Cu" "F.Mask" "F.Paste")
			(net "GND")
		)
		(pad "2" smd rect
			(at -0.40005 0)
			(size 0.4572 0.508)
			(layers "F.Cu" "F.Mask" "F.Paste")
			(net "P12V_STBY")
		)
	)
	(footprint ""
		(layer "F.Cu")
		(at 69.774816 -439.03646 90)
		(property "Reference" "C77"
			(at 1.382522 0.064516 90)
			(unlocked yes)
			(layer "F.SilkS")
			(effects
				(font
					(size 0.7874 0.5842)
					(thickness 0.1524)
				)
				(justify left)
			)
		)
		(property "Value" ""
			(at 0 0 90)
			(layer "F.Fab")
			(effects
				(font
					(size 1.27 1.27)
				)
			)
		)
		(duplicate_pad_numbers_are_jumpers no)
		(fp_line
			(start 0.7874 -0.4064)
			(end 0.7874 0.4064)
			(stroke
				(width 0.1524)
				(type default)
			)
			(layer "F.SilkS")
		)
		(fp_line
			(start -0.7874 -0.4064)
			(end 0.7874 -0.4064)
			(stroke
				(width 0.1524)
				(type default)
			)
			(layer "F.SilkS")
		)
		(fp_line
			(start 0 0.381)
			(end 0 -0.381)
			(stroke
				(width 0.1524)
				(type default)
			)
			(layer "F.SilkS")
		)
		(fp_line
			(start 0.7874 0.4064)
			(end -0.7874 0.4064)
			(stroke
				(width 0.1524)
				(type default)
			)
			(layer "F.SilkS")
		)
		(fp_line
			(start -0.7874 0.4064)
			(end -0.7874 -0.4064)
			(stroke
				(width 0.1524)
				(type default)
			)
			(layer "F.SilkS")
		)
		(fp_poly
			(pts
				(xy -0.5334 0.254) (xy -0.635 0.254) (xy -0.635 0.2286) (xy -0.635 -0.254) (xy -0.5334 -0.254) (xy -0.5334 -0.2794)
				(xy 0.5334 -0.2794) (xy 0.5334 -0.254) (xy 0.635 -0.254) (xy 0.635 0.254) (xy 0.5334 0.254) (xy 0.5334 0.2794)
				(xy -0.508 0.2794) (xy -0.5334 0.2794)
			)
			(stroke
				(width 0)
				(type default)
			)
			(fill no)
			(layer "F.CrtYd")
		)
		(pad "1" smd rect
			(at 0.40005 0 90)
			(size 0.4572 0.508)
			(layers "F.Cu" "F.Mask" "F.Paste")
			(net "P12V")
		)
		(pad "2" smd rect
			(at -0.40005 0 90)
			(size 0.4572 0.508)
			(layers "F.Cu" "F.Mask" "F.Paste")
			(net "GND")
		)
	)
	(footprint ""
		(layer "F.Cu")
		(at 91.399868 -331.16012)
		(property "Reference" "H26"
			(at -5.1308 -5.23113 0)
			(unlocked yes)
			(layer "F.SilkS")
			(effects
				(font
					(size 0.7874 0.5842)
					(thickness 0.1524)
				)
				(justify left)
			)
		)
		(property "Value" ""
			(at 0 0 0)
			(layer "F.Fab")
			(effects
				(font
					(size 1.27 1.27)
				)
			)
		)
		(duplicate_pad_numbers_are_jumpers no)
		(fp_circle
			(center 0 0)
			(end 4.826 0)
			(stroke
				(width 0.1524)
				(type default)
			)
			(fill no)
			(layer "F.SilkS")
		)
		(fp_circle
			(center 0 0)
			(end 4.826 0)
			(stroke
				(width 0.1524)
				(type default)
			)
			(fill no)
			(layer "B.SilkS")
		)
		(fp_poly
			(pts
				(arc
					(start 0 4.0132)
					(mid 0 -4.0132)
					(end 0 4.0132)
				)
			)
			(stroke
				(width 0)
				(type default)
			)
			(fill no)
			(layer "F.CrtYd")
		)
		(pad "" np_thru_hole circle
			(at 0 0)
			(size 8.001 8.001)
			(drill 8.001)
			(layers "*.Cu" "*.Mask")
			(clearance 0.381)
			(thermal_gap 0.381)
		)
		(zone
			(layers "F.Cu" "B.Cu" "In1.Cu" "In2.Cu" "In3.Cu" "In4.Cu" "In5.Cu" "In6.Cu")
			(hatch none 0.5)
			(connect_pads
				(clearance 0)
			)
			(min_thickness 0.25)
			(keepout
				(tracks not_allowed)
				(vias allowed)
				(pads allowed)
				(copperpour not_allowed)
				(footprints allowed)
			)
			(placement
				(enabled no)
				(sheetname "")
			)
			(fill
				(thermal_gap 0.5)
				(thermal_bridge_width 0.5)
				(island_removal_mode 0)
			)
			(polygon
				(pts
					(arc
						(start 91.399868 -326.63892)
						(mid 91.399868 -335.68132)
						(end 91.399868 -326.63892)
					)
				)
			)
		)
	)
	(footprint ""
		(layer "F.Cu")
		(at 4.204208 -414.966912 -90)
		(property "Reference" "R152"
			(at -1.520444 0.16764 90)
			(unlocked yes)
			(layer "F.SilkS")
			(effects
				(font
					(size 0.7874 0.5842)
					(thickness 0.1524)
				)
				(justify left)
			)
		)
		(property "Value" ""
			(at 0 0 270)
			(layer "F.Fab")
			(effects
				(font
					(size 1.27 1.27)
				)
			)
		)
		(duplicate_pad_numbers_are_jumpers no)
		(fp_line
			(start -0.7874 0.4064)
			(end -0.7874 -0.4064)
			(stroke
				(width 0.1524)
				(type default)
			)
			(layer "F.SilkS")
		)
		(fp_line
			(start 0.7874 0.4064)
			(end -0.7874 0.4064)
			(stroke
				(width 0.1524)
				(type default)
			)
			(layer "F.SilkS")
		)
		(fp_line
			(start -0.7874 -0.4064)
			(end 0.7874 -0.4064)
			(stroke
				(width 0.1524)
				(type default)
			)
			(layer "F.SilkS")
		)
		(fp_line
			(start 0.7874 -0.4064)
			(end 0.7874 0.4064)
			(stroke
				(width 0.1524)
				(type default)
			)
			(layer "F.SilkS")
		)
		(fp_poly
			(pts
				(xy -0.508 0.2794) (xy -0.508 0.2286) (xy -0.635 0.2286) (xy -0.635 -0.254) (xy -0.5334 -0.254)
				(xy -0.5334 -0.2794) (xy 0.5334 -0.2794) (xy 0.5334 -0.254) (xy 0.635 -0.254) (xy 0.635 0.254) (xy 0.5334 0.254)
				(xy 0.5334 0.2794)
			)
			(stroke
				(width 0)
				(type default)
			)
			(fill no)
			(layer "F.CrtYd")
		)
		(pad "1" smd rect
			(at 0.40005 0 270)
			(size 0.4572 0.508)
			(layers "F.Cu" "F.Mask" "F.Paste")
			(net "N42132933")
		)
		(pad "2" smd rect
			(at -0.40005 0 270)
			(size 0.4572 0.508)
			(layers "F.Cu" "F.Mask" "F.Paste")
			(net "GND")
		)
	)
	(footprint ""
		(layer "F.Cu")
		(at 25.931622 -94.464886)
		(property "Reference" "R69"
			(at -4.080256 -0.075692 0)
			(unlocked yes)
			(layer "F.SilkS")
			(effects
				(font
					(size 0.7874 0.5842)
					(thickness 0.1524)
				)
				(justify left)
			)
		)
		(property "Value" ""
			(at 0 0 0)
			(layer "F.Fab")
			(effects
				(font
					(size 1.27 1.27)
				)
			)
		)
		(duplicate_pad_numbers_are_jumpers no)
		(fp_line
			(start -0.7874 -0.4064)
			(end 0.7874 -0.4064)
			(stroke
				(width 0.1524)
				(type default)
			)
			(layer "F.SilkS")
		)
		(fp_line
			(start -0.7874 0.4064)
			(end -0.7874 -0.4064)
			(stroke
				(width 0.1524)
				(type default)
			)
			(layer "F.SilkS")
		)
		(fp_line
			(start 0.7874 -0.4064)
			(end 0.7874 0.4064)
			(stroke
				(width 0.1524)
				(type default)
			)
			(layer "F.SilkS")
		)
		(fp_line
			(start 0.7874 0.4064)
			(end -0.7874 0.4064)
			(stroke
				(width 0.1524)
				(type default)
			)
			(layer "F.SilkS")
		)
		(fp_poly
			(pts
				(xy -0.508 0.2794) (xy -0.508 0.2286) (xy -0.635 0.2286) (xy -0.635 -0.254) (xy -0.5334 -0.254)
				(xy -0.5334 -0.2794) (xy 0.5334 -0.2794) (xy 0.5334 -0.254) (xy 0.635 -0.254) (xy 0.635 0.254) (xy 0.5334 0.254)
				(xy 0.5334 0.2794)
			)
			(stroke
				(width 0)
				(type default)
			)
			(fill no)
			(layer "F.CrtYd")
		)
		(pad "1" smd rect
			(at 0.40005 0)
			(size 0.4572 0.508)
			(layers "F.Cu" "F.Mask" "F.Paste")
			(net "PSU2_RESET")
		)
		(pad "2" smd rect
			(at -0.40005 0)
			(size 0.4572 0.508)
			(layers "F.Cu" "F.Mask" "F.Paste")
			(net "GND")
		)
	)
)
